FILE_TYPE = CONNECTIVITY;
{Allegro Design Entry HDL 17.2-2016 S081 (4005846) 1/11/2022}
"PAGE_NUMBER" = 176;
0"NC";
1"GND\g";
2"GND\g";
3"GND\g";
4"GND\g";
5"GND\g";
6"GND\g";
7"GND\g";
8"GND\g";
9"P5V_STBY\g";
10"P3V3_STBY\g";
11"GND\g";
12"GND\g";
13"P12V_STBY\g";
14"PVDDCR_CPU1_P0\g";
15"PVDDCR_CPU1_P0\g";
16"GND\g";
17"PVDDCR_CPU1_P0_VCC1";
18"SW_PVDDCR_CPU1_P0_BOOTR2";
19"SW_PVDDCR_CPU1_P0_SW2";
20"SW_PVDDCR_CPU1_P0_BOOT2_R";
21"GND\g";
22"SW_PVDDCR_CPU1_P0_BOOTR1";
23"GND\g";
24"GND\g";
25"PVDDCR_CPU1_P0\g";
26"IND_CPU1_P0_CPL2";
27"NC_PVDDCR_CPU1_P0_GL2_1";
28"NC_PVDDCR_CPU1_P0_GL1_1";
29"SW_PVDDCR_CPU1_P0_BOOT1";
30"NC_PVDDCR_CPU1_P0_DNC1";
31"SW_PVDDCR_CPU1_P0_SW1_RC";
32"IND_CPU1_P0_CPL1";
33"SW_PVDDCR_CPU1_P0_SW2_RC";
34"NC_PVDDCR_CPU1_P0_GL1_2";
35"NC_PVDDCR_CPU1_P0_GL2_2";
36"GND\g";
37"GND\g";
38"NC_PVDDCR_CPU1_P0_DNC2";
39"PVDDCR_CPU1_P0_TEMP0";
40"PVDDCR_CPU1_P0_IMON1";
41"PVDDCR_CPU1_P0_TEMP0";
42"PVDDCR_CPU1_P0_PWM1";
43"PVDDCR_CPU1_P0_IMON2";
44"PVDDCR_CPU1_P0_VCCS"CDS_PHYS_NET_NAME"PVCCIN_CPU0_VREF";
45"PVDDCR_CPU1_P0_VCC2";
46"PVDDCR_CPU1_P0_LSET2";
47"PVDDCR_CPU1_P0_LSET1";
48"PVDDCR_CPU1_P0_PVCC\g";
49"SW_P12V_STBY_PVDDCR_CPU1_P0_FLT\g";
50"IND_CPU1_P0_CPL1";
51"GND\g";
52"IND_CPU1_P0_CPL5";
53"SW_PVDDCR_CPU1_P0_SW1";
54"SW_PVDDCR_CPU1_P0_BOOT1_R";
55"PVDDCR_CPU1_P0_PVCC\g";
56"PVDDCR_CPU1_P0_VOS1";
57"SW_P12V_STBY_PVDDCR_CPU1_P0_FLT\g";
58"SW_PVDDCR_CPU1_P0_BOOT2";
59"PVDDCR_CPU1_P0_VOS2";
60"PVDDCR_CPU1_P0_PWM2";
61"PVDDCR_CPU1_P0_VCCS"CDS_PHYS_NET_NAME"PVCCIN_CPU0_VREF";
%"UNIVERSAL_GND"
"1","(-8875,775)","0","pure_quanta_power","I1";
;
CDS_LIB"pure_quanta_power"
HDL_POWER"GND";
"A"1;
%"VCC_CORE"
"1","(-1575,4575)","0","pure_quanta_power","I106";
;
HDL_POWER"PVDDCR_CPU1_P0"
CDS_LIB"pure_quanta_power";
"A"14;
%"UNIVERSAL_GND"
"1","(-1575,3900)","0","pure_quanta_power","I107";
;
CDS_LIB"pure_quanta_power"
HDL_POWER"GND";
"A"23;
%"Q_CAP"
"1","(-1875,4250)","0","pure_quanta","I108";
;
LOCATION"PC105_1"
$SEC"1"
CDS_SEC"1"
TOLERANCE"20%"
VALUE"22UF"
VOLTAGE"4V"
PACK_TYPE"0805"
MATERIAL"X6S"
CDS_LIB"pure_quanta"
PART_NUMBER"TMP_QCH622KMEA01";
"B"
$PN"2"23;
"A"
$PN"1"14;
%"Q_CAP"
"1","(-2300,4250)","0","pure_quanta","I109";
;
LOCATION"PC102_1"
$SEC"1"
CDS_SEC"1"
MATERIAL"X6S"
TOLERANCE"20%"
VALUE"22UF"
PART_NUMBER"TMP_QCH622KMEA01"
VOLTAGE"4V"
PACK_TYPE"0805"
CDS_LIB"pure_quanta";
"B"
$PN"2"23;
"A"
$PN"1"14;
%"Q_CAP"
"1","(-2700,4250)","0","pure_quanta","I111";
;
LOCATION"PC99"
$SEC"1"
CDS_SEC"1"
MATERIAL"X7R"
TOLERANCE"10%"
VALUE"0.1UF"
PART_NUMBER"CH4104K1B00"
VOLTAGE"25V"
PACK_TYPE"0402"
CDS_LIB"pure_quanta";
"B"
$PN"2"23;
"A"
$PN"1"14;
%"Q_RES"
"1","(-4575,3550)","0","pure_quanta","I112";
;
LOCATION"PR84"
$SEC"1"
CDS_SEC"1"
PART_NUMBER"CS00002JB38"
TOLERANCE"5%"
PACK_TYPE"0402LF"
MATERIAL"CHIP"
WATTAGE"1/16W"
VALUE"0"
CDS_LIB"pure_quanta";
"B"
$PN"2"14;
"A"
$PN"1"56;
%"Q_RES"
"1","(-4650,600)","0","pure_quanta","I124";
;
LOCATION"PR83"
$SEC"1"
CDS_SEC"1"
WATTAGE"1/16W"
MATERIAL"CHIP"
TOLERANCE"5%"
VALUE"0"
PART_NUMBER"CS00002JB38"
PACK_TYPE"0402LF"
CDS_LIB"pure_quanta";
"B"
$PN"2"25;
"A"
$PN"1"59;
%"UNIVERSAL_GND"
"1","(-2025,950)","0","pure_quanta_power","I125";
;
CDS_LIB"pure_quanta_power"
HDL_POWER"GND";
"A"24;
%"VCC_CORE"
"1","(-2025,1600)","0","pure_quanta_power","I126";
;
HDL_POWER"PVDDCR_CPU1_P0"
CDS_LIB"pure_quanta_power";
"A"25;
%"Q_CAP"
"1","(-2025,1300)","0","pure_quanta","I127";
;
LOCATION"PC108_2"
$SEC"1"
CDS_SEC"1"
MATERIAL"X6S"
TOLERANCE"20%"
VALUE"22UF"
PART_NUMBER"TMP_QCH622KMEA01"
VOLTAGE"4V"
PACK_TYPE"0805"
CDS_LIB"pure_quanta";
"B"
$PN"2"24;
"A"
$PN"1"25;
%"Q_CAP"
"1","(-2450,1300)","0","pure_quanta","I128";
;
LOCATION"PC106_2"
$SEC"1"
CDS_SEC"1"
MATERIAL"X6S"
TOLERANCE"20%"
VALUE"22UF"
PART_NUMBER"TMP_QCH622KMEA01"
VOLTAGE"4V"
PACK_TYPE"0805"
CDS_LIB"pure_quanta";
"B"
$PN"2"24;
"A"
$PN"1"25;
%"UNIVERSAL_GND"
"1","(-8850,3725)","0","pure_quanta_power","I13";
;
CDS_LIB"pure_quanta_power"
HDL_POWER"GND";
"A"2;
%"Q_INDUCTOR4P_14"
"1","(-3875,1375)","0","pure_quanta","I137";
;
LOCATION"PL11"
$SEC"1"
CDS_SEC"1"
MATERIAL"IND"
PART_NUMBER"CV+15^0TZ04"
PART_TYPE"SMLF"
VALUE"150NH"
NEEDS_NO_SIZE"TRUE"
CDS_LIB"pure_quanta";
"1"
$PN"1"19;
"4"
$PN"4"25;
"3"
$PN"3"26;
"2"
$PN"2"32;
%"Q_INDUCTOR4P_14"
"1","(-4175,4325)","0","pure_quanta","I138";
;
LOCATION"PL10"
$SEC"1"
CDS_SEC"1"
PART_TYPE"SMLF"
VALUE"150NH"
PART_NUMBER"CV+15^0TZ04"
MATERIAL"IND"
NEEDS_NO_SIZE"TRUE"
CDS_LIB"pure_quanta";
"1"
$PN"1"53;
"4"
$PN"4"14;
"3"
$PN"3"50;
"2"
$PN"2"52;
%"Q_CAP"
"1","(-9475,1175)","0","pure_quanta","I139";
;
LOCATION"PC83_2"
$SEC"1"
CDS_SEC"1"
MATERIAL"X7R"
TOLERANCE"10%"
VALUE"0.1UF"
PART_NUMBER"CH4104K1B00"
VOLTAGE"25V"
PACK_TYPE"0402"
CDS_LIB"pure_quanta";
"B"
$PN"2"12;
"A"
$PN"1"61;
%"Q_RES"
"2","(-8850,3950)","2","pure_quanta","I14";
;
LOCATION"PR78"
$SEC"1"
CDS_SEC"1"
WATTAGE"1/16W"
MATERIAL"EMPTY"
TOLERANCE"1%"
VALUE"8.87K"
PART_NUMBER"CS28872FB01"
PACK_TYPE"0402LF"
CDS_LIB"pure_quanta";
"A"
$PN"1"47;
"B"
$PN"2"2;
%"Q_CAP"
"1","(-9350,4075)","0","pure_quanta","I140";
;
LOCATION"PC84_1"
$SEC"1"
CDS_SEC"1"
PART_NUMBER"CH4104K1B00"
MATERIAL"X7R"
TOLERANCE"10%"
VALUE"0.1UF"
VOLTAGE"25V"
PACK_TYPE"0402"
CDS_LIB"pure_quanta";
"B"
$PN"2"11;
"A"
$PN"1"44;
%"Q_CAP"
"1","(-4950,4675)","0","pure_quanta","I141";
;
LOCATION"PC92"
$SEC"1"
CDS_SEC"1"
TOLERANCE"10%"
MATERIAL"X7R"
VALUE"0.22UF"
PART_NUMBER"CH4223K1B00"
VOLTAGE"16V"
PACK_TYPE"0402"
CDS_LIB"pure_quanta";
"B"
$PN"2"22;
"A"
$PN"1"54;
%"Q_RES"
"1","(-5675,4800)","0","pure_quanta","I142";
;
LOCATION"PR82"
$SEC"1"
CDS_SEC"1"
TOLERANCE"1%"
WATTAGE"1/16W"
MATERIAL"CHIP"
PACK_TYPE"0402LF"
VALUE"4.7"
PART_NUMBER"CS-4702FB19"
CDS_LIB"pure_quanta";
"B"
$PN"2"54;
"A"
$PN"1"29;
%"Q_CAP"
"1","(-4900,1725)","0","pure_quanta","I143";
;
LOCATION"PC94"
$SEC"1"
CDS_SEC"1"
MATERIAL"X7R"
TOLERANCE"10%"
VALUE"0.22UF"
PART_NUMBER"CH4223K1B00"
VOLTAGE"16V"
PACK_TYPE"0402"
CDS_LIB"pure_quanta";
"B"
$PN"2"18;
"A"
$PN"1"20;
%"Q_RES"
"1","(-5700,1850)","0","pure_quanta","I144";
;
LOCATION"PR81"
$SEC"1"
CDS_SEC"1"
TOLERANCE"1%"
MATERIAL"CHIP"
WATTAGE"1/16W"
PACK_TYPE"0402LF"
VALUE"4.7"
PART_NUMBER"CS-4702FB19"
CDS_LIB"pure_quanta";
"B"
$PN"2"20;
"A"
$PN"1"58;
%"Q_CAPP"
"1","(-3075,3000)","0","pure_quanta","I148";
;
LOCATION"PC97"
$SEC"1"
CDS_SEC"1"
VALUE"220UF"
VOLTAGE"4V"
TOLERANCE"20%"
MATERIAL"SPCAP"
PART_NUMBER"CH122KM8801"
PACK_TYPE"SMLF"
CDS_LIB"pure_quanta";
"A"
$PN"1"15;
"B"
$PN"2"16;
%"UNIVERSAL_GND"
"1","(-2125,2625)","0","pure_quanta_power","I149";
;
CDS_LIB"pure_quanta_power"
HDL_POWER"GND";
"A"16;
%"Q_CAPP"
"1","(-2750,3000)","0","pure_quanta","I150";
;
LOCATION"PC98"
$SEC"1"
CDS_SEC"1"
VALUE"220UF"
TOLERANCE"20%"
VOLTAGE"4V"
MATERIAL"SPCAP"
PART_NUMBER"CH122KM8801"
PACK_TYPE"SMLF"
CDS_LIB"pure_quanta";
"A"
$PN"1"15;
"B"
$PN"2"16;
%"Q_CAPP"
"1","(-2425,3000)","0","pure_quanta","I151";
;
LOCATION"PC100"
$SEC"1"
CDS_SEC"1"
PACK_TYPE"SMLF"
VOLTAGE"4V"
VALUE"220UF"
TOLERANCE"20%"
MATERIAL"SPCAP"
PART_NUMBER"CH122KM8801"
CDS_LIB"pure_quanta";
"A"
$PN"1"15;
"B"
$PN"2"16;
%"VCC_CORE"
"1","(-2125,3300)","0","pure_quanta_power","I152";
;
HDL_POWER"PVDDCR_CPU1_P0"
CDS_LIB"pure_quanta_power";
"A"15;
%"Q_CAPP"
"1","(-2125,3000)","0","pure_quanta","I153";
;
LOCATION"PC103"
$SEC"1"
CDS_SEC"1"
PACK_TYPE"SMLF"
VOLTAGE"4V"
VALUE"220UF"
TOLERANCE"20%"
MATERIAL"SPCAP"
PART_NUMBER"CH122KM8801"
CDS_LIB"pure_quanta";
"A"
$PN"1"15;
"B"
$PN"2"16;
%"Q_CAP"
"1","(-6150,5350)","0","pure_quanta","I154";
;
LOCATION"PC85_1"
$SEC"1"
CDS_SEC"1"
MATERIAL"X7R"
TOLERANCE"10%"
VALUE"0.1UF"
PART_NUMBER"CH4104K1B00"
VOLTAGE"25V"
PACK_TYPE"0402"
CDS_LIB"pure_quanta";
"B"
$PN"2"51;
"A"
$PN"1"49;
%"Q_CAP"
"1","(-6125,2400)","0","pure_quanta","I155";
;
LOCATION"PC86_2"
$SEC"1"
CDS_SEC"1"
PART_NUMBER"CH4104K1B00"
MATERIAL"X7R"
TOLERANCE"10%"
VALUE"0.1UF"
VOLTAGE"25V"
PACK_TYPE"0402"
CDS_LIB"pure_quanta";
"B"
$PN"2"21;
"A"
$PN"1"57;
%"Q_CAP"
"1","(-8700,4900)","0","pure_quanta","I156";
;
LOCATION"PC79"
$SEC"1"
CDS_SEC"1"
MATERIAL"X6S"
TOLERANCE"10%"
VALUE"2.2UF"
PART_NUMBER"CH5222KEB01"
VOLTAGE"10V"
PACK_TYPE"C0402"
CDS_LIB"pure_quanta";
"B"
$PN"2"3;
"A"
$PN"1"17;
%"UNIVERSAL_GND"
"1","(-8700,4700)","0","pure_quanta_power","I157";
;
CDS_LIB"pure_quanta_power"
HDL_POWER"GND";
"A"3;
%"UNIVERSAL_GND"
"1","(-8350,5150)","0","pure_quanta_power","I158";
;
CDS_LIB"pure_quanta_power"
HDL_POWER"GND";
"A"4;
%"Q_RES"
"2","(-8700,5375)","0","pure_quanta","I159";
;
LOCATION"PR79"
$SEC"1"
CDS_SEC"1"
WATTAGE"1/16W"
MATERIAL"CHIP"
TOLERANCE"1%"
VALUE"2.2"
PART_NUMBER"CS-2202FB00"
PACK_TYPE"0402LF"
CDS_LIB"pure_quanta";
"A"
$PN"1"55;
"B"
$PN"2"17;
%"Q_CAP"
"1","(-8350,5400)","0","pure_quanta","I160";
;
LOCATION"PC81_C1P0_1"
$SEC"1"
CDS_SEC"1"
MATERIAL"X6S"
TOLERANCE"10%"
VALUE"2.2UF"
PART_NUMBER"CH5222KEB01"
VOLTAGE"10V"
PACK_TYPE"C0402"
CDS_LIB"pure_quanta";
"B"
$PN"2"4;
"A"
$PN"1"55;
%"Q_CAP"
"1","(-8600,1925)","0","pure_quanta","I162";
;
LOCATION"PC80"
$SEC"1"
CDS_SEC"1"
MATERIAL"X6S"
TOLERANCE"10%"
VALUE"2.2UF"
PART_NUMBER"CH5222KEB01"
VOLTAGE"10V"
PACK_TYPE"C0402"
CDS_LIB"pure_quanta";
"B"
$PN"2"5;
"A"
$PN"1"45;
%"UNIVERSAL_GND"
"1","(-8600,1725)","0","pure_quanta_power","I163";
;
CDS_LIB"pure_quanta_power"
HDL_POWER"GND";
"A"5;
%"UNIVERSAL_GND"
"1","(-8250,2225)","0","pure_quanta_power","I164";
;
CDS_LIB"pure_quanta_power"
HDL_POWER"GND";
"A"6;
%"Q_RES"
"2","(-8600,2475)","0","pure_quanta","I165";
;
LOCATION"PR80"
$SEC"1"
CDS_SEC"1"
WATTAGE"1/16W"
MATERIAL"CHIP"
TOLERANCE"1%"
VALUE"2.2"
PART_NUMBER"CS-2202FB00"
PACK_TYPE"0402LF"
CDS_LIB"pure_quanta";
"A"
$PN"1"48;
"B"
$PN"2"45;
%"Q_CAP"
"1","(-8250,2500)","0","pure_quanta","I166";
;
LOCATION"PC82_C1P0_2"
$SEC"1"
CDS_SEC"1"
MATERIAL"X6S"
TOLERANCE"10%"
VALUE"2.2UF"
PART_NUMBER"CH5222KEB01"
VOLTAGE"10V"
PACK_TYPE"C0402"
CDS_LIB"pure_quanta";
"B"
$PN"2"6;
"A"
$PN"1"48;
%"Q_CAPP"
"1","(-3425,3000)","0","pure_quanta","I168";
;
LOCATION"PC102"
$SEC"1"
CDS_SEC"1"
PACK_TYPE"SMLF"
VOLTAGE"4V"
TOLERANCE"20%"
VALUE"220UF"
MATERIAL"SPCAP"
PART_NUMBER"CH122KM8801"
CDS_LIB"pure_quanta";
"A"
$PN"1"15;
"B"
$PN"2"16;
%"Q_CAP"
"1","(-5600,4275)","0","pure_quanta","I170";
;
LOCATION"PC189"
$SEC"1"
CDS_SEC"1"
MATERIAL"EMPTY"
TOLERANCE"10%"
VALUE"560PF"
PART_NUMBER"CH1566K1B09"
VOLTAGE"50V"
PACK_TYPE"C0402"
CDS_LIB"pure_quanta";
"B"
$PN"2"31;
"A"
$PN"1"53;
%"Q_RES"
"2","(-5600,3825)","0","pure_quanta","I171";
;
LOCATION"PR506"
$SEC"1"
CDS_SEC"1"
PART_NUMBER"CS-1504FB00"
MATERIAL"EMPTY"
WATTAGE"1/8W"
TOLERANCE"1%"
PACK_TYPE"0402LF"
VALUE"1.5"
CDS_LIB"pure_quanta";
"A"
$PN"1"31;
"B"
$PN"2"7;
%"UNIVERSAL_GND"
"1","(-5600,3600)","0","pure_quanta_power","I172";
;
CDS_LIB"pure_quanta_power"
HDL_POWER"GND";
"A"7;
%"Q_CAP"
"1","(-5600,1325)","0","pure_quanta","I173";
;
LOCATION"PC190"
$SEC"1"
CDS_SEC"1"
MATERIAL"EMPTY"
TOLERANCE"10%"
VALUE"560PF"
PART_NUMBER"CH1566K1B09"
VOLTAGE"50V"
PACK_TYPE"C0402"
CDS_LIB"pure_quanta";
"B"
$PN"2"33;
"A"
$PN"1"19;
%"Q_RES"
"2","(-5600,875)","0","pure_quanta","I174";
;
LOCATION"PR507"
$SEC"1"
CDS_SEC"1"
WATTAGE"1/8W"
MATERIAL"EMPTY"
TOLERANCE"1%"
VALUE"1.5"
PART_NUMBER"CS-1504FB00"
PACK_TYPE"0402LF"
CDS_LIB"pure_quanta";
"A"
$PN"1"33;
"B"
$PN"2"8;
%"UNIVERSAL_GND"
"1","(-5600,650)","0","pure_quanta_power","I175";
;
CDS_LIB"pure_quanta_power"
HDL_POWER"GND";
"A"8;
%"VCC_CORE"
"1","(-8600,2900)","0","pure_quanta_power","I182";
;
HDL_POWER"PVDDCR_CPU1_P0_PVCC"
CDS_LIB"pure_quanta_power";
"A"48;
%"VCC_CORE"
"1","(-8500,5975)","0","pure_quanta_power","I183";
;
HDL_POWER"PVDDCR_CPU1_P0_PVCC"
CDS_LIB"pure_quanta_power";
"A"55;
%"Q_RES"
"1","(-9350,5775)","1","pure_quanta","I184";
;
LOCATION"PR442"
$SEC"1"
CDS_SEC"1"
WATTAGE"1/16W"
MATERIAL"CHIP"
TOLERANCE"5%"
VALUE"0"
PART_NUMBER"CS00002JB38"
PACK_TYPE"0402LF"
CDS_LIB"pure_quanta";
"B"
$PN"2"9;
"A"
$PN"1"55;
%"VCC_CORE"
"1","(-9350,5975)","0","pure_quanta_power","I185";
;
HDL_POWER"P5V_STBY"
CDS_LIB"pure_quanta_power";
"A"9;
%"VCC_CORE"
"1","(-9000,5975)","0","pure_quanta_power","I186";
;
HDL_POWER"P3V3_STBY"
CDS_LIB"pure_quanta_power";
"A"10;
%"Q_RES"
"1","(-9000,5775)","1","pure_quanta","I187";
;
LOCATION"PR443"
$SEC"1"
CDS_SEC"1"
WATTAGE"1/16W"
MATERIAL"EMPTY"
TOLERANCE"5%"
VALUE"0"
PART_NUMBER"CS00002JB38"
PACK_TYPE"0402LF"
CDS_LIB"pure_quanta";
"B"
$PN"2"10;
"A"
$PN"1"55;
%"Q_RES"
"2","(-1575,4225)","0","pure_quanta","I188";
;
LOCATION"PR444"
$SEC"1"
CDS_SEC"1"
WATTAGE"1/16W"
MATERIAL"CHIP"
TOLERANCE"1%"
VALUE"1K"
PART_NUMBER"TMP_QCS21002FB24"
PACK_TYPE"0402LF"
CDS_LIB"pure_quanta";
"A"
$PN"1"14;
"B"
$PN"2"23;
%"UNIVERSAL_GND"
"1","(-6300,775)","0","pure_quanta_power","I19";
;
CDS_LIB"pure_quanta_power"
HDL_POWER"GND";
"A"37;
%"Q_RES"
"2","(-8875,1000)","2","pure_quanta","I2";
;
LOCATION"PR77"
$SEC"1"
CDS_SEC"1"
WATTAGE"1/16W"
MATERIAL"EMPTY"
TOLERANCE"1%"
VALUE"8.87K"
PART_NUMBER"CS28872FB01"
PACK_TYPE"0402LF"
CDS_LIB"pure_quanta";
"A"
$PN"1"46;
"B"
$PN"2"1;
%"ISL99390FRZTR5935"
"1","(-6925,4450)","0","pure_quanta","I21";
;
LOCATION"PU13"
$SEC"1"
CDS_SEC"1"
PART_TYPE"SMLF"
MATERIAL"IC"
PART_NUMBER"AL099390004"
VALUE"ISL99390FRZ-TR5935"
CDS_LIB"pure_quanta"
NEEDS_NO_SIZE"TRUE"
CDS_LMAN_SYM_OUTLINE"-300,700,250,-650";
"PGND2"
$PN"7_9-20_24"36;
"GL2"
$PN"41"27;
"GL1"
$PN"6"28;
"DNC"
$PN"31"30;
"EN"
$PN"35"17;
"PGND3"
$PN"40"36;
"VOS"
$PN"1"56;
"VIN2"
$PN"30"49;
"PGND1"
$PN"5"36;
"SW"
$PN"10_19"53;
"LSET"
$PN"37"47;
"IOUT"
$PN"38"40;
"TOUT_FLT"
$PN"36"41;
"PVCC"
$PN"4"55;
"PHASE"
$PN"32"22;
"VIN1"
$PN"25_29"49;
"BOOT"
$PN"33"29;
"AGND"
$PN"2"36;
"VCC"
$PN"3"17;
"REFIN"
$PN"39"44;
"PWM"
$PN"34"42;
%"Q_CAP"
"1","(-5725,2400)","0","pure_quanta","I23";
;
LOCATION"PC88_2"
$SEC"1"
CDS_SEC"1"
TOLERANCE"10%"
VALUE"1UF"
VOLTAGE"25V"
MATERIAL"X6S"
PACK_TYPE"C0402"
PART_NUMBER"CH5104KEB02"
CDS_LIB"pure_quanta";
"B"
$PN"2"21;
"A"
$PN"1"57;
%"Q_CAP"
"1","(-5325,2400)","0","pure_quanta","I24";
;
LOCATION"PC90_2"
$SEC"1"
CDS_SEC"1"
PART_NUMBER"CH6104KEA00"
MATERIAL"X6S"
TOLERANCE"10%"
VALUE"10UF"
VOLTAGE"25V"
PACK_TYPE"C0805"
CDS_LIB"pure_quanta";
"B"
$PN"2"21;
"A"
$PN"1"57;
%"UNIVERSAL_GND"
"1","(-6275,3725)","0","pure_quanta_power","I25";
;
CDS_LIB"pure_quanta_power"
HDL_POWER"GND";
"A"36;
%"UNIVERSAL_GND"
"1","(-9350,3875)","0","pure_quanta_power","I26";
;
CDS_LIB"pure_quanta_power"
HDL_POWER"GND";
"A"11;
%"UNIVERSAL_GND"
"1","(-9475,900)","0","pure_quanta_power","I4";
;
CDS_LIB"pure_quanta_power"
HDL_POWER"GND";
"A"12;
%"Q_CAP"
"1","(-5750,5350)","0","pure_quanta","I41";
;
LOCATION"PC87_1"
$SEC"1"
CDS_SEC"1"
TOLERANCE"10%"
MATERIAL"X6S"
VALUE"1UF"
PART_NUMBER"CH5104KEB02"
VOLTAGE"25V"
PACK_TYPE"C0402"
CDS_LIB"pure_quanta";
"B"
$PN"2"51;
"A"
$PN"1"49;
%"Q_CAP"
"1","(-4925,2400)","0","pure_quanta","I46";
;
LOCATION"PC93_2"
$SEC"1"
CDS_SEC"1"
PART_NUMBER"CH6104KEA00"
VALUE"10UF"
TOLERANCE"10%"
VOLTAGE"25V"
PACK_TYPE"C0805"
MATERIAL"X6S"
CDS_LIB"pure_quanta";
"B"
$PN"2"21;
"A"
$PN"1"57;
%"Q_CAP"
"1","(-4550,2400)","0","pure_quanta","I47";
;
LOCATION"PC96_2"
$SEC"1"
CDS_SEC"1"
MATERIAL"X6S"
PACK_TYPE"C0805"
PART_NUMBER"CH6104KEA00"
TOLERANCE"10%"
VALUE"10UF"
VOLTAGE"25V"
CDS_LIB"pure_quanta";
"B"
$PN"2"21;
"A"
$PN"1"57;
%"UNIVERSAL_GND"
"1","(-4550,2025)","0","pure_quanta_power","I48";
;
CDS_LIB"pure_quanta_power"
HDL_POWER"GND";
"A"21;
%"VCC_CORE"
"1","(-4550,2750)","0","pure_quanta_power","I49";
;
HDL_POWER"SW_P12V_STBY_PVDDCR_CPU1_P0_FLT"
CDS_LIB"pure_quanta_power";
"A"57;
%"UNIVERSAL_GND"
"1","(-4350,4975)","0","pure_quanta_power","I64";
;
CDS_LIB"pure_quanta_power"
HDL_POWER"GND";
"A"51;
%"Q_CAP"
"1","(-5350,5350)","0","pure_quanta","I65";
;
LOCATION"PC89_1"
$SEC"1"
CDS_SEC"1"
PART_NUMBER"CH6104KEA00"
MATERIAL"X6S"
TOLERANCE"10%"
VALUE"10UF"
VOLTAGE"25V"
PACK_TYPE"C0805"
CDS_LIB"pure_quanta";
"B"
$PN"2"51;
"A"
$PN"1"49;
%"Q_CAP"
"1","(-4950,5350)","0","pure_quanta","I66";
;
LOCATION"PC91_1"
$SEC"1"
CDS_SEC"1"
PART_NUMBER"CH6104KEA00"
VALUE"10UF"
MATERIAL"X6S"
TOLERANCE"10%"
VOLTAGE"25V"
PACK_TYPE"C0805"
CDS_LIB"pure_quanta";
"B"
$PN"2"51;
"A"
$PN"1"49;
%"Q_CAP"
"1","(-4575,5350)","0","pure_quanta","I67";
;
LOCATION"PC95_1"
$SEC"1"
CDS_SEC"1"
VALUE"10UF"
PART_NUMBER"CH6104KEA00"
MATERIAL"X6S"
PACK_TYPE"C0805"
TOLERANCE"10%"
VOLTAGE"25V"
CDS_LIB"pure_quanta";
"B"
$PN"2"51;
"A"
$PN"1"49;
%"VCC_CORE"
"1","(-4350,5700)","0","pure_quanta_power","I68";
;
HDL_POWER"SW_P12V_STBY_PVDDCR_CPU1_P0_FLT"
CDS_LIB"pure_quanta_power";
"A"49;
%"VCC_CORE"
"1","(-3050,5700)","0","pure_quanta_power","I73";
;
HDL_POWER"P12V_STBY"
CDS_LIB"pure_quanta_power";
"A"13;
%"Q_CAPP"
"1","(-4150,5350)","0","pure_quanta","I74";
;
LOCATION"PC101"
$SEC"1"
CDS_SEC"1"
PART_NUMBER"CC72204MD02"
MATERIAL"OSCON"
VOLTAGE"25V"
PACK_TYPE"THLF"
TOLERANCE"20%"
VALUE"220UF"
CDS_LIB"pure_quanta";
"A"
$PN"1"49;
"B"
$PN"2"51;
%"Q_INDUCTOR"
"1","(-3350,5625)","0","pure_quanta","I75";
;
LOCATION"PL12"
$SEC"1"
CDS_SEC"1"
PART_NUMBER"CVA50^0MZ09"
MATERIAL"IND"
VALUE"50NH/86A"
PACK_TYPE"SMLF"
CDS_LIB"pure_quanta"
NEEDS_NO_SIZE"TRUE";
"1"
$PN"1"49;
"2"
$PN"2"13;
%"Q_CAPP"
"1","(-3750,5350)","0","pure_quanta","I76";
;
LOCATION"PC104"
$SEC"1"
CDS_SEC"1"
MATERIAL"OSCON"
TOLERANCE"20%"
VALUE"220UF"
PART_NUMBER"CC72204MD02"
VOLTAGE"25V"
PACK_TYPE"THLF"
CDS_LIB"pure_quanta";
"A"
$PN"1"49;
"B"
$PN"2"51;
%"ISL99390FRZTR5935"
"1","(-6950,1500)","0","pure_quanta","I87";
;
LOCATION"PU2"
$SEC"1"
CDS_SEC"1"
VALUE"ISL99390FRZ-TR5935"
PART_TYPE"SMLF"
PART_NUMBER"AL099390004"
MATERIAL"IC"
CDS_LIB"pure_quanta"
NEEDS_NO_SIZE"TRUE"
CDS_LMAN_SYM_OUTLINE"-300,700,250,-650";
"PGND2"
$PN"7_9-20_24"37;
"GL2"
$PN"41"35;
"GL1"
$PN"6"34;
"DNC"
$PN"31"38;
"EN"
$PN"35"45;
"PGND3"
$PN"40"37;
"VOS"
$PN"1"59;
"VIN2"
$PN"30"57;
"PGND1"
$PN"5"37;
"SW"
$PN"10_19"19;
"LSET"
$PN"37"46;
"IOUT"
$PN"38"43;
"TOUT_FLT"
$PN"36"39;
"PVCC"
$PN"4"48;
"PHASE"
$PN"32"18;
"VIN1"
$PN"25_29"57;
"BOOT"
$PN"33"58;
"AGND"
$PN"2"37;
"VCC"
$PN"3"45;
"REFIN"
$PN"39"61;
"PWM"
$PN"34"60;
END.
